# S9S_MB_2U (Grand Teton) — schematic netlist excerpt (pin names and nets, part order shuffled) for the footprints in the layout excerpt that follows; sources: Cadence DE-HDL packaged netlist, KiCad conversion of 03242023_DA0F0TMBIJ0_F0T_Motherboard_J_brd_V01_OCP.brd

C887  Q_CAP_DIFFBUS  DIFF BUS_0.22UF 6.3V 20% X6S  pkg C0201  page 174 : \1\ = P5E_CPU0_PE3_TX_C_DP<7> ; \2\ = P5E_CPU0_PE3_TX_DP<7>
PR561  Q_RES  100 1% CHIP  pkg 0402LF  page 284 : A = VSENSE_PVCCFA_EHV_FIVRA_CPU1_DP ; B = PVCCFA_EHV_FIVRA_CPU1
R563  Q_RES  22 1% CHIP  pkg 0402LF  page 209 : A = CLK_100M_OCP_SFF_0_R_DP ; B = CLK_100M_OCP_SFF_0_DP

(kicad_pcb
	(version 20260206)
	(generator "pcbnew")
	(generator_version "10.0")
	(general
		(thickness 1.6)
		(legacy_teardrops no)
	)
	(paper "A4")
	(title_block
		(title "03242023_DA0F0TMBIJ0_F0T_Motherboard_J_brd_V01_OCP.brd")
		(comment 1 "Grand Teton / footprints 1926-1928 of 6105")
	)
	(layers
		(0 "F.Cu" signal "TOP")
		(4 "In1.Cu" signal "GND")
		(6 "In2.Cu" signal "IN1")
		(8 "In3.Cu" signal "GND1")
		(10 "In4.Cu" signal "IN2")
		(12 "In5.Cu" signal "GND2")
		(14 "In6.Cu" signal "IN3")
		(16 "In7.Cu" signal "GND3")
		(18 "In8.Cu" signal "VCC")
		(20 "In9.Cu" signal "VCC1")
		(22 "In10.Cu" signal "GND4")
		(24 "In11.Cu" signal "IN4")
		(26 "In12.Cu" signal "GND5")
		(28 "In13.Cu" signal "IN5")
		(30 "In14.Cu" signal "GND6")
		(32 "In15.Cu" signal "IN6")
		(34 "In16.Cu" signal "GND7")
		(2 "B.Cu" signal "BOTTOM")
		(9 "F.Adhes" user "F.Adhesive")
		(11 "B.Adhes" user "B.Adhesive")
		(13 "F.Paste" user "Package Geometry/Pastemask Top")
		(15 "B.Paste" user "Package Geometry/Pastemask Bottom")
		(5 "F.SilkS" user "Ref Des/Silkscreen Top")
		(7 "B.SilkS" user "Ref Des/Silkscreen Bottom")
		(1 "F.Mask" user "Board Geometry/Soldermask Top")
		(3 "B.Mask" user "Board Geometry/Soldermask Bottom")
		(17 "Dwgs.User" user "User.Drawings")
		(19 "Cmts.User" user "User.Comments")
		(21 "Eco1.User" user "User.Eco1")
		(23 "Eco2.User" user "User.Eco2")
		(25 "Edge.Cuts" user "Board Geometry/Outline")
		(27 "Margin" user)
		(31 "F.CrtYd" user "Package Geometry/Place Bound Top")
		(29 "B.CrtYd" user "Package Geometry/Place Bound Bottom")
		(35 "F.Fab" user "Ref Des/Assembly Top")
		(33 "B.Fab" user "Ref Des/Assembly Bottom")
	)
	(footprint ""
		(layer "F.Cu")
		(at 56.950102 -337.022186 180)
		(property "Reference" "PR561"
			(at 0 0 180)
			(layer "F.SilkS")
			(hide yes)
			(effects
				(font
					(size 1.27 1.27)
				)
			)
		)
		(property "Value" ""
			(at 0 0 180)
			(layer "F.Fab")
			(effects
				(font
					(size 1.27 1.27)
				)
			)
		)
		(duplicate_pad_numbers_are_jumpers no)
		(fp_line
			(start 0.7874 0.4064)
			(end -0.7874 0.4064)
			(stroke
				(width 0.1524)
				(type default)
			)
			(layer "F.SilkS")
		)
		(fp_line
			(start 0.7874 -0.4064)
			(end 0.7874 0.4064)
			(stroke
				(width 0.1524)
				(type default)
			)
			(layer "F.SilkS")
		)
		(fp_line
			(start -0.7874 0.4064)
			(end -0.7874 -0.4064)
			(stroke
				(width 0.1524)
				(type default)
			)
			(layer "F.SilkS")
		)
		(fp_line
			(start -0.7874 -0.4064)
			(end 0.7874 -0.4064)
			(stroke
				(width 0.1524)
				(type default)
			)
			(layer "F.SilkS")
		)
		(fp_line
			(start 0.67945 0.3048)
			(end 0.120396 0.3048)
			(stroke
				(width 0.1)
				(type default)
			)
			(layer "F.Fab")
		)
		(fp_line
			(start 0.67945 -0.3048)
			(end 0.67945 0.3048)
			(stroke
				(width 0.1)
				(type default)
			)
			(layer "F.Fab")
		)
		(fp_line
			(start 0.12065 -0.2794)
			(end 0.12065 -0.3048)
			(stroke
				(width 0.1)
				(type default)
			)
			(layer "F.Fab")
		)
		(fp_line
			(start 0.12065 -0.3048)
			(end 0.67945 -0.3048)
			(stroke
				(width 0.1)
				(type default)
			)
			(layer "F.Fab")
		)
		(fp_line
			(start 0.120396 0.3048)
			(end 0.120396 0.2794)
			(stroke
				(width 0.1)
				(type default)
			)
			(layer "F.Fab")
		)
		(fp_line
			(start 0.120396 0.2794)
			(end -0.12065 0.2794)
			(stroke
				(width 0.1)
				(type default)
			)
			(layer "F.Fab")
		)
		(fp_line
			(start -0.12065 0.3048)
			(end -0.67945 0.3048)
			(stroke
				(width 0.1)
				(type default)
			)
			(layer "F.Fab")
		)
		(fp_line
			(start -0.12065 0.2794)
			(end -0.12065 0.3048)
			(stroke
				(width 0.1)
				(type default)
			)
			(layer "F.Fab")
		)
		(fp_line
			(start -0.12065 -0.2794)
			(end 0.12065 -0.2794)
			(stroke
				(width 0.1)
				(type default)
			)
			(layer "F.Fab")
		)
		(fp_line
			(start -0.12065 -0.305054)
			(end -0.12065 -0.2794)
			(stroke
				(width 0.1)
				(type default)
			)
			(layer "F.Fab")
		)
		(fp_line
			(start -0.67945 0.3048)
			(end -0.67945 -0.305054)
			(stroke
				(width 0.1)
				(type default)
			)
			(layer "F.Fab")
		)
		(fp_line
			(start -0.67945 -0.305054)
			(end -0.12065 -0.305054)
			(stroke
				(width 0.1)
				(type default)
			)
			(layer "F.Fab")
		)
		(pad "1" smd circle
			(at -0.40005 0 180)
			(size 0 0)
			(layers "F.Cu" "F.Mask" "F.Paste")
			(net "VSENSE_PVCCFA_EHV_FIVRA_CPU1_DP")
		)
		(pad "2" smd circle
			(at 0.40005 0 180)
			(size 0 0)
			(layers "F.Cu" "F.Mask" "F.Paste")
			(net "PVCCFA_EHV_FIVRA_CPU1")
		)
	)
	(footprint ""
		(layer "F.Cu")
		(at 228.760782 -127.399542 180)
		(property "Reference" "R563"
			(at 0 0 180)
			(layer "F.SilkS")
			(hide yes)
			(effects
				(font
					(size 1.27 1.27)
				)
			)
		)
		(property "Value" ""
			(at 0 0 180)
			(layer "F.Fab")
			(effects
				(font
					(size 1.27 1.27)
				)
			)
		)
		(duplicate_pad_numbers_are_jumpers no)
		(fp_line
			(start 0.7874 0.4064)
			(end -0.7874 0.4064)
			(stroke
				(width 0.1524)
				(type default)
			)
			(layer "F.SilkS")
		)
		(fp_line
			(start 0.7874 -0.107442)
			(end 0.7874 0.4064)
			(stroke
				(width 0.1524)
				(type default)
			)
			(layer "F.SilkS")
		)
		(fp_line
			(start -0.433578 -0.4064)
			(end 0.330962 -0.4064)
			(stroke
				(width 0.1524)
				(type default)
			)
			(layer "F.SilkS")
		)
		(fp_line
			(start -0.7874 0.4064)
			(end -0.7874 -0.041402)
			(stroke
				(width 0.1524)
				(type default)
			)
			(layer "F.SilkS")
		)
		(fp_line
			(start 0.67945 0.3048)
			(end 0.120396 0.3048)
			(stroke
				(width 0.1)
				(type default)
			)
			(layer "F.Fab")
		)
		(fp_line
			(start 0.67945 -0.3048)
			(end 0.67945 0.3048)
			(stroke
				(width 0.1)
				(type default)
			)
			(layer "F.Fab")
		)
		(fp_line
			(start 0.12065 -0.2794)
			(end 0.12065 -0.3048)
			(stroke
				(width 0.1)
				(type default)
			)
			(layer "F.Fab")
		)
		(fp_line
			(start 0.12065 -0.3048)
			(end 0.67945 -0.3048)
			(stroke
				(width 0.1)
				(type default)
			)
			(layer "F.Fab")
		)
		(fp_line
			(start 0.120396 0.3048)
			(end 0.120396 0.2794)
			(stroke
				(width 0.1)
				(type default)
			)
			(layer "F.Fab")
		)
		(fp_line
			(start 0.120396 0.2794)
			(end -0.12065 0.2794)
			(stroke
				(width 0.1)
				(type default)
			)
			(layer "F.Fab")
		)
		(fp_line
			(start -0.12065 0.3048)
			(end -0.67945 0.3048)
			(stroke
				(width 0.1)
				(type default)
			)
			(layer "F.Fab")
		)
		(fp_line
			(start -0.12065 0.2794)
			(end -0.12065 0.3048)
			(stroke
				(width 0.1)
				(type default)
			)
			(layer "F.Fab")
		)
		(fp_line
			(start -0.12065 -0.2794)
			(end 0.12065 -0.2794)
			(stroke
				(width 0.1)
				(type default)
			)
			(layer "F.Fab")
		)
		(fp_line
			(start -0.12065 -0.305054)
			(end -0.12065 -0.2794)
			(stroke
				(width 0.1)
				(type default)
			)
			(layer "F.Fab")
		)
		(fp_line
			(start -0.67945 0.3048)
			(end -0.67945 -0.305054)
			(stroke
				(width 0.1)
				(type default)
			)
			(layer "F.Fab")
		)
		(fp_line
			(start -0.67945 -0.305054)
			(end -0.12065 -0.305054)
			(stroke
				(width 0.1)
				(type default)
			)
			(layer "F.Fab")
		)
		(pad "1" smd circle
			(at -0.40005 0 180)
			(size 0 0)
			(layers "F.Cu" "F.Mask" "F.Paste")
			(net "CLK_100M_OCP_SFF_0_R_DP")
		)
		(pad "2" smd circle
			(at 0.40005 0 180)
			(size 0 0)
			(layers "F.Cu" "F.Mask" "F.Paste")
			(net "CLK_100M_OCP_SFF_0_DP")
		)
	)
	(footprint ""
		(layer "F.Cu")
		(at 398.16405 -408.517344 -90)
		(property "Reference" "C887"
			(at 0 0 270)
			(layer "F.SilkS")
			(hide yes)
			(effects
				(font
					(size 1.27 1.27)
				)
			)
		)
		(property "Value" ""
			(at 0 0 270)
			(layer "F.Fab")
			(effects
				(font
					(size 1.27 1.27)
				)
			)
		)
		(duplicate_pad_numbers_are_jumpers no)
		(fp_line
			(start -0.299974 0.150114)
			(end -0.299974 -0.150114)
			(stroke
				(width 0.1)
				(type default)
			)
			(layer "F.Fab")
		)
		(fp_line
			(start 0.299974 0.150114)
			(end -0.299974 0.150114)
			(stroke
				(width 0.1)
				(type default)
			)
			(layer "F.Fab")
		)
		(fp_line
			(start -0.299974 -0.150114)
			(end 0.299974 -0.150114)
			(stroke
				(width 0.1)
				(type default)
			)
			(layer "F.Fab")
		)
		(fp_line
			(start 0.299974 -0.150114)
			(end 0.299974 0.150114)
			(stroke
				(width 0.1)
				(type default)
			)
			(layer "F.Fab")
		)
		(pad "1" smd rect
			(at -0.2667 0 270)
			(size 0.3048 0.381)
			(layers "F.Cu" "F.Mask" "F.Paste")
			(net "P5E_CPU0_PE3_TX_C_DP<7>")
		)
		(pad "2" smd rect
			(at 0.2667 0 270)
			(size 0.3048 0.381)
			(layers "F.Cu" "F.Mask" "F.Paste")
			(net "P5E_CPU0_PE3_TX_DP<7>")
		)
	)
)
